(kicad_pcb
	(version 20260206)
	(generator "pcbnew")
	(generator_version "10.0")
	(general
		(thickness 1.6)
		(legacy_teardrops no)
	)
	(paper "A4")
	(title_block
		(title "fcb — Lightning_FCB_BRD.brd")
		(comment 1 "Lightning (Wiwynn / Facebook NVMe JBOF) / footprint 383 of 495 (CN9), pads 1-56 of 56")
	)
	(layers
		(0 "F.Cu" signal "TOP")
		(4 "In1.Cu" signal "L2GND")
		(6 "In2.Cu" signal "L3VCC")
		(2 "B.Cu" signal "BOTTOM")
		(9 "F.Adhes" user "F.Adhesive")
		(11 "B.Adhes" user "B.Adhesive")
		(13 "F.Paste" user "Package Geometry/Pastemask Top")
		(15 "B.Paste" user "Package Geometry/Pastemask Bottom")
		(5 "F.SilkS" user "Ref Des/Silkscreen Top")
		(7 "B.SilkS" user "Ref Des/Silkscreen Bottom")
		(1 "F.Mask" user "Board Geometry/Soldermask Top")
		(3 "B.Mask" user "Board Geometry/Soldermask Bottom")
		(17 "Dwgs.User" user "User.Drawings")
		(19 "Cmts.User" user "User.Comments")
		(21 "Eco1.User" user "User.Eco1")
		(23 "Eco2.User" user "User.Eco2")
		(25 "Edge.Cuts" user "Board Geometry/Outline")
		(27 "Margin" user)
		(31 "F.CrtYd" user "Package Geometry/Place Bound Top")
		(29 "B.CrtYd" user "Package Geometry/Place Bound Bottom")
		(35 "F.Fab" user "Ref Des/Assembly Top")
		(33 "B.Fab" user "Ref Des/Assembly Bottom")
	)
	(footprint ""
		(layer "F.Cu")
		(at 20.500086 -56.999886 -90)
		(property "Reference" "CN9"
			(at 0 0 270)
			(layer "F.SilkS")
			(hide yes)
			(effects
				(font
					(size 1.27 1.27)
				)
			)
		)
		(property "Value" "FCI-CONN52-4R-1-GP"
			(at -30.89656 -6.096 270)
			(unlocked yes)
			(layer "F.Fab")
			(hide yes)
			(effects
				(font
					(size 1.016 1.016)
					(thickness 0.1524)
				)
			)
		)
		(property "Device Type" "51952-220LF"
			(at -30.89656 -7.62 270)
			(unlocked yes)
			(layer "F.Fab")
			(hide yes)
			(effects
				(font
					(size 1.016 1.016)
					(thickness 0.1524)
				)
			)
		)
		(duplicate_pad_numbers_are_jumpers no)
		(pad "" np_thru_hole circle
			(at -26.67 0 270)
			(size 0.254 0.254)
			(drill 3.2004)
			(layers "*.Cu" "*.Mask")
			(clearance 1.8288)
			(thermal_gap 1.8288)
		)
		(pad "" np_thru_hole circle
			(at -21.59 0 270)
			(size 0.254 0.254)
			(drill 2.5146)
			(layers "*.Cu" "*.Mask")
			(clearance 1.4859)
			(thermal_gap 1.4859)
		)
		(pad "" np_thru_hole circle
			(at 21.59 0 270)
			(size 0.254 0.254)
			(drill 2.5146)
			(layers "*.Cu" "*.Mask")
			(clearance 1.4859)
			(thermal_gap 1.4859)
		)
		(pad "" np_thru_hole circle
			(at 26.67 0 270)
			(size 0.254 0.254)
			(drill 3.2004)
			(layers "*.Cu" "*.Mask")
			(clearance 1.8288)
			(thermal_gap 1.8288)
		)
		(pad "A1" thru_hole circle
			(at -5.08 0 270)
			(size 1.4478 1.4478)
			(drill 1.0414)
			(layers "*.Cu" "*.Mask")
			(remove_unused_layers no)
			(net "I2C_C_SDA_CONN_R")
			(clearance 0.1524)
			(thermal_gap 0.1524)
		)
		(pad "A2" thru_hole circle
			(at -2.54 0 270)
			(size 1.4478 1.4478)
			(drill 1.0414)
			(layers "*.Cu" "*.Mask")
			(remove_unused_layers no)
			(net "GND")
			(clearance 0.1524)
			(thermal_gap 0.1524)
		)
		(pad "A3" thru_hole circle
			(at 0 0 270)
			(size 1.4478 1.4478)
			(drill 1.0414)
			(layers "*.Cu" "*.Mask")
			(remove_unused_layers no)
			(net "I2C_C_SCL_CONN_R")
			(clearance 0.1524)
			(thermal_gap 0.1524)
		)
		(pad "A4" thru_hole circle
			(at 2.54 0 270)
			(size 1.4478 1.4478)
			(drill 1.0414)
			(layers "*.Cu" "*.Mask")
			(remove_unused_layers no)
			(net "GND")
			(clearance 0.1524)
			(thermal_gap 0.1524)
		)
		(pad "A5" thru_hole circle
			(at 5.08 0 270)
			(size 1.4478 1.4478)
			(drill 1.0414)
			(layers "*.Cu" "*.Mask")
			(remove_unused_layers no)
			(net "PWM_EXP_1B")
			(clearance 0.1524)
			(thermal_gap 0.1524)
		)
		(pad "B1" thru_hole circle
			(at -5.08 -2.54 270)
			(size 1.4478 1.4478)
			(drill 1.0414)
			(layers "*.Cu" "*.Mask")
			(remove_unused_layers no)
			(net "GND")
			(clearance 0.1524)
			(thermal_gap 0.1524)
		)
		(pad "B2" thru_hole circle
			(at -2.54 -2.54 270)
			(size 1.4478 1.4478)
			(drill 1.0414)
			(layers "*.Cu" "*.Mask")
			(remove_unused_layers no)
			(net "PWM_EXP_1A")
			(clearance 0.1524)
			(thermal_gap 0.1524)
		)
		(pad "B3" thru_hole circle
			(at 0 -2.54 270)
			(size 1.4478 1.4478)
			(drill 1.0414)
			(layers "*.Cu" "*.Mask")
			(remove_unused_layers no)
			(net "GND")
			(clearance 0.1524)
			(thermal_gap 0.1524)
		)
		(pad "B4" thru_hole circle
			(at 2.54 -2.54 270)
			(size 1.4478 1.4478)
			(drill 1.0414)
			(layers "*.Cu" "*.Mask")
			(remove_unused_layers no)
			(net "SELF_1B_HB")
			(clearance 0.1524)
			(thermal_gap 0.1524)
		)
		(pad "B5" thru_hole circle
			(at 5.08 -2.54 270)
			(size 1.4478 1.4478)
			(drill 1.0414)
			(layers "*.Cu" "*.Mask")
			(remove_unused_layers no)
			(net "GND")
			(clearance 0.1524)
			(thermal_gap 0.1524)
		)
		(pad "C1" thru_hole circle
			(at -5.08 -5.08 270)
			(size 1.4478 1.4478)
			(drill 1.0414)
			(layers "*.Cu" "*.Mask")
			(remove_unused_layers no)
			(net "P12VU_2490_EN_1")
			(clearance 0.1524)
			(thermal_gap 0.1524)
		)
		(pad "C2" thru_hole circle
			(at -2.54 -5.08 270)
			(size 1.4478 1.4478)
			(drill 1.0414)
			(layers "*.Cu" "*.Mask")
			(remove_unused_layers no)
			(net "P12VU_2490_EN_2")
			(clearance 0.1524)
			(thermal_gap 0.1524)
		)
		(pad "C3" thru_hole circle
			(at 0 -5.08 270)
			(size 1.4478 1.4478)
			(drill 1.0414)
			(layers "*.Cu" "*.Mask")
			(remove_unused_layers no)
			(net "SELF_1A_HB")
			(clearance 0.1524)
			(thermal_gap 0.1524)
		)
		(pad "C4" thru_hole circle
			(at 2.54 -5.08 270)
			(size 1.4478 1.4478)
			(drill 1.0414)
			(layers "*.Cu" "*.Mask")
			(remove_unused_layers no)
			(net "SEB_PEER_1A_HB")
			(clearance 0.1524)
			(thermal_gap 0.1524)
		)
		(pad "C5" thru_hole circle
			(at 5.08 -5.08 270)
			(size 1.4478 1.4478)
			(drill 1.0414)
			(layers "*.Cu" "*.Mask")
			(remove_unused_layers no)
			(net "SEB_PEER_1B_HB")
			(clearance 0.1524)
			(thermal_gap 0.1524)
		)
		(pad "D1" thru_hole circle
			(at -5.08 -7.62 270)
			(size 1.4478 1.4478)
			(drill 1.0414)
			(layers "*.Cu" "*.Mask")
			(remove_unused_layers no)
			(net "PEER_TRAY PRESENT_UPPER")
			(clearance 0.1524)
			(thermal_gap 0.1524)
		)
		(pad "D2" thru_hole circle
			(at -2.54 -7.62 270)
			(size 1.4478 1.4478)
			(drill 1.0414)
			(layers "*.Cu" "*.Mask")
			(remove_unused_layers no)
			(net "UPPER_TRAY_ID")
			(clearance 0.1524)
			(thermal_gap 0.1524)
		)
		(pad "D3" thru_hole circle
			(at 0 -7.62 270)
			(size 1.4478 1.4478)
			(drill 1.0414)
			(layers "*.Cu" "*.Mask")
			(remove_unused_layers no)
			(net "FCB_HW_REVISION")
			(clearance 0.1524)
			(thermal_gap 0.1524)
		)
		(pad "D4" thru_hole circle
			(at 2.54 -7.62 270)
			(size 1.4478 1.4478)
			(drill 1.0414)
			(layers "*.Cu" "*.Mask")
			(remove_unused_layers no)
			(net "SD_LATCH_RELEASE_U")
			(clearance 0.1524)
			(thermal_gap 0.1524)
		)
		(pad "D5" thru_hole circle
			(at 5.08 -7.62 270)
			(size 1.4478 1.4478)
			(drill 1.0414)
			(layers "*.Cu" "*.Mask")
			(remove_unused_layers no)
			(net "SELF_TRAY_PRESENT_UPPER")
			(clearance 0.1524)
			(thermal_gap 0.1524)
		)
		(pad "P1_1" thru_hole circle
			(at -15.88008 0 270)
			(size 1.4478 1.4478)
			(drill 1.0414)
			(layers "*.Cu" "*.Mask")
			(remove_unused_layers no)
			(net "P12VU")
			(clearance 0.1524)
			(thermal_gap 0.1524)
		)
		(pad "P1_2" thru_hole circle
			(at -15.88008 -2.54 270)
			(size 1.4478 1.4478)
			(drill 1.0414)
			(layers "*.Cu" "*.Mask")
			(remove_unused_layers no)
			(net "P12VU")
			(clearance 0.1524)
			(thermal_gap 0.1524)
		)
		(pad "P1_3" thru_hole circle
			(at -15.88008 -5.08 270)
			(size 1.4478 1.4478)
			(drill 1.0414)
			(layers "*.Cu" "*.Mask")
			(remove_unused_layers no)
			(net "P12VU")
			(clearance 0.1524)
			(thermal_gap 0.1524)
		)
		(pad "P1_4" thru_hole circle
			(at -15.88008 -7.62 270)
			(size 1.4478 1.4478)
			(drill 1.0414)
			(layers "*.Cu" "*.Mask")
			(remove_unused_layers no)
			(net "P12VU")
			(clearance 0.1524)
			(thermal_gap 0.1524)
		)
		(pad "P1_5" thru_hole circle
			(at -13.34008 0 270)
			(size 1.4478 1.4478)
			(drill 1.0414)
			(layers "*.Cu" "*.Mask")
			(remove_unused_layers no)
			(net "P12VU")
			(clearance 0.1524)
			(thermal_gap 0.1524)
		)
		(pad "P1_6" thru_hole circle
			(at -13.34008 -2.54 270)
			(size 1.4478 1.4478)
			(drill 1.0414)
			(layers "*.Cu" "*.Mask")
			(remove_unused_layers no)
			(net "P12VU")
			(clearance 0.1524)
			(thermal_gap 0.1524)
		)
		(pad "P1_7" thru_hole circle
			(at -13.34008 -5.08 270)
			(size 1.4478 1.4478)
			(drill 1.0414)
			(layers "*.Cu" "*.Mask")
			(remove_unused_layers no)
			(net "P12VU")
			(clearance 0.1524)
			(thermal_gap 0.1524)
		)
		(pad "P1_8" thru_hole circle
			(at -13.34008 -7.62 270)
			(size 1.4478 1.4478)
			(drill 1.0414)
			(layers "*.Cu" "*.Mask")
			(remove_unused_layers no)
			(net "P12VU")
			(clearance 0.1524)
			(thermal_gap 0.1524)
		)
		(pad "P2_1" thru_hole circle
			(at -10.80008 0 270)
			(size 1.4478 1.4478)
			(drill 1.0414)
			(layers "*.Cu" "*.Mask")
			(remove_unused_layers no)
			(net "P12VU")
			(clearance 0.1524)
			(thermal_gap 0.1524)
		)
		(pad "P2_2" thru_hole circle
			(at -10.80008 -2.54 270)
			(size 1.4478 1.4478)
			(drill 1.0414)
			(layers "*.Cu" "*.Mask")
			(remove_unused_layers no)
			(net "P12VU")
			(clearance 0.1524)
			(thermal_gap 0.1524)
		)
		(pad "P2_3" thru_hole circle
			(at -10.80008 -5.08 270)
			(size 1.4478 1.4478)
			(drill 1.0414)
			(layers "*.Cu" "*.Mask")
			(remove_unused_layers no)
			(net "P12VU")
			(clearance 0.1524)
			(thermal_gap 0.1524)
		)
		(pad "P2_4" thru_hole circle
			(at -10.80008 -7.62 270)
			(size 1.4478 1.4478)
			(drill 1.0414)
			(layers "*.Cu" "*.Mask")
			(remove_unused_layers no)
			(net "P12VU")
			(clearance 0.1524)
			(thermal_gap 0.1524)
		)
		(pad "P2_5" thru_hole circle
			(at -8.26008 0 270)
			(size 1.4478 1.4478)
			(drill 1.0414)
			(layers "*.Cu" "*.Mask")
			(remove_unused_layers no)
			(net "P12VU")
			(clearance 0.1524)
			(thermal_gap 0.1524)
		)
		(pad "P2_6" thru_hole circle
			(at -8.26008 -2.54 270)
			(size 1.4478 1.4478)
			(drill 1.0414)
			(layers "*.Cu" "*.Mask")
			(remove_unused_layers no)
			(net "P12VU")
			(clearance 0.1524)
			(thermal_gap 0.1524)
		)
		(pad "P2_7" thru_hole circle
			(at -8.26008 -5.08 270)
			(size 1.4478 1.4478)
			(drill 1.0414)
			(layers "*.Cu" "*.Mask")
			(remove_unused_layers no)
			(net "P12VU")
			(clearance 0.1524)
			(thermal_gap 0.1524)
		)
		(pad "P2_8" thru_hole circle
			(at -8.26008 -7.62 270)
			(size 1.4478 1.4478)
			(drill 1.0414)
			(layers "*.Cu" "*.Mask")
			(remove_unused_layers no)
			(net "P12VU")
			(clearance 0.1524)
			(thermal_gap 0.1524)
		)
		(pad "P3_1" thru_hole circle
			(at 8.26008 0 270)
			(size 1.4478 1.4478)
			(drill 1.0414)
			(layers "*.Cu" "*.Mask")
			(remove_unused_layers no)
			(net "GND")
			(clearance 0.1524)
			(thermal_gap 0.1524)
		)
		(pad "P3_2" thru_hole circle
			(at 8.26008 -2.54 270)
			(size 1.4478 1.4478)
			(drill 1.0414)
			(layers "*.Cu" "*.Mask")
			(remove_unused_layers no)
			(net "GND")
			(clearance 0.1524)
			(thermal_gap 0.1524)
		)
		(pad "P3_3" thru_hole circle
			(at 8.26008 -5.08 270)
			(size 1.4478 1.4478)
			(drill 1.0414)
			(layers "*.Cu" "*.Mask")
			(remove_unused_layers no)
			(net "GND")
			(clearance 0.1524)
			(thermal_gap 0.1524)
		)
		(pad "P3_4" thru_hole circle
			(at 8.26008 -7.62 270)
			(size 1.4478 1.4478)
			(drill 1.0414)
			(layers "*.Cu" "*.Mask")
			(remove_unused_layers no)
			(net "GND")
			(clearance 0.1524)
			(thermal_gap 0.1524)
		)
		(pad "P3_5" thru_hole circle
			(at 10.80008 0 270)
			(size 1.4478 1.4478)
			(drill 1.0414)
			(layers "*.Cu" "*.Mask")
			(remove_unused_layers no)
			(net "GND")
			(clearance 0.1524)
			(thermal_gap 0.1524)
		)
		(pad "P3_6" thru_hole circle
			(at 10.80008 -2.54 270)
			(size 1.4478 1.4478)
			(drill 1.0414)
			(layers "*.Cu" "*.Mask")
			(remove_unused_layers no)
			(net "GND")
			(clearance 0.1524)
			(thermal_gap 0.1524)
		)
		(pad "P3_7" thru_hole circle
			(at 10.80008 -5.08 270)
			(size 1.4478 1.4478)
			(drill 1.0414)
			(layers "*.Cu" "*.Mask")
			(remove_unused_layers no)
			(net "GND")
			(clearance 0.1524)
			(thermal_gap 0.1524)
		)
		(pad "P3_8" thru_hole circle
			(at 10.80008 -7.62 270)
			(size 1.4478 1.4478)
			(drill 1.0414)
			(layers "*.Cu" "*.Mask")
			(remove_unused_layers no)
			(net "GND")
			(clearance 0.1524)
			(thermal_gap 0.1524)
		)
		(pad "P4_1" thru_hole circle
			(at 13.34008 0 270)
			(size 1.4478 1.4478)
			(drill 1.0414)
			(layers "*.Cu" "*.Mask")
			(remove_unused_layers no)
			(net "GND")
			(clearance 0.1524)
			(thermal_gap 0.1524)
		)
		(pad "P4_2" thru_hole circle
			(at 13.34008 -2.54 270)
			(size 1.4478 1.4478)
			(drill 1.0414)
			(layers "*.Cu" "*.Mask")
			(remove_unused_layers no)
			(net "GND")
			(clearance 0.1524)
			(thermal_gap 0.1524)
		)
		(pad "P4_3" thru_hole circle
			(at 13.34008 -5.08 270)
			(size 1.4478 1.4478)
			(drill 1.0414)
			(layers "*.Cu" "*.Mask")
			(remove_unused_layers no)
			(net "GND")
			(clearance 0.1524)
			(thermal_gap 0.1524)
		)
		(pad "P4_4" thru_hole circle
			(at 13.34008 -7.62 270)
			(size 1.4478 1.4478)
			(drill 1.0414)
			(layers "*.Cu" "*.Mask")
			(remove_unused_layers no)
			(net "GND")
			(clearance 0.1524)
			(thermal_gap 0.1524)
		)
		(pad "P4_5" thru_hole circle
			(at 15.88008 0 270)
			(size 1.4478 1.4478)
			(drill 1.0414)
			(layers "*.Cu" "*.Mask")
			(remove_unused_layers no)
			(net "GND")
			(clearance 0.1524)
			(thermal_gap 0.1524)
		)
		(pad "P4_6" thru_hole circle
			(at 15.88008 -2.54 270)
			(size 1.4478 1.4478)
			(drill 1.0414)
			(layers "*.Cu" "*.Mask")
			(remove_unused_layers no)
			(net "GND")
			(clearance 0.1524)
			(thermal_gap 0.1524)
		)
		(pad "P4_7" thru_hole circle
			(at 15.88008 -5.08 270)
			(size 1.4478 1.4478)
			(drill 1.0414)
			(layers "*.Cu" "*.Mask")
			(remove_unused_layers no)
			(net "GND")
			(clearance 0.1524)
			(thermal_gap 0.1524)
		)
		(pad "P4_8" thru_hole circle
			(at 15.88008 -7.62 270)
			(size 1.4478 1.4478)
			(drill 1.0414)
			(layers "*.Cu" "*.Mask")
			(remove_unused_layers no)
			(net "GND")
			(clearance 0.1524)
			(thermal_gap 0.1524)
		)
	)
)
